(kicad_pcb
	(version 20260206)
	(generator "pcbnew")
	(generator_version "10.0")
	(general
		(thickness 1.6)
		(legacy_teardrops no)
	)
	(paper "A4")
	(title_block
		(title "peb — Lightning_PEB_BRD.brd")
		(comment 1 "Lightning (Wiwynn / Facebook NVMe JBOF) / footprints 8-14 of 2563")
	)
	(layers
		(0 "F.Cu" signal "TOP")
		(4 "In1.Cu" signal "L2GND")
		(6 "In2.Cu" signal "L3")
		(8 "In3.Cu" signal "L4VCC")
		(10 "In4.Cu" signal "L5VCC")
		(12 "In5.Cu" signal "L6")
		(14 "In6.Cu" signal "L7GND")
		(2 "B.Cu" signal "BOTTOM")
		(9 "F.Adhes" user "F.Adhesive")
		(11 "B.Adhes" user "B.Adhesive")
		(13 "F.Paste" user "Package Geometry/Pastemask Top")
		(15 "B.Paste" user "Package Geometry/Pastemask Bottom")
		(5 "F.SilkS" user "Ref Des/Silkscreen Top")
		(7 "B.SilkS" user "Ref Des/Silkscreen Bottom")
		(1 "F.Mask" user "Board Geometry/Soldermask Top")
		(3 "B.Mask" user "Board Geometry/Soldermask Bottom")
		(17 "Dwgs.User" user "User.Drawings")
		(19 "Cmts.User" user "User.Comments")
		(21 "Eco1.User" user "User.Eco1")
		(23 "Eco2.User" user "User.Eco2")
		(25 "Edge.Cuts" user "Board Geometry/Outline")
		(27 "Margin" user)
		(31 "F.CrtYd" user "Package Geometry/Place Bound Top")
		(29 "B.CrtYd" user "Package Geometry/Place Bound Bottom")
		(35 "F.Fab" user "Ref Des/Assembly Top")
		(33 "B.Fab" user "Ref Des/Assembly Bottom")
	)
	(footprint ""
		(layer "F.Cu")
		(at 336.68462 -36.705286 180)
		(property "Reference" "Q28"
			(at 0 0 180)
			(layer "F.SilkS")
			(hide yes)
			(effects
				(font
					(size 1.27 1.27)
				)
			)
		)
		(property "Value" "2N7002K-1-GP"
			(at 0.127 -8.9662 180)
			(unlocked yes)
			(layer "F.Fab")
			(hide yes)
			(effects
				(font
					(size 1.016 1.016)
					(thickness 0.1524)
				)
			)
		)
		(property "Device Type" "SOT23DGS2D4H44"
			(at 0.127 -10.4902 180)
			(unlocked yes)
			(layer "F.Fab")
			(hide yes)
			(effects
				(font
					(size 1.016 1.016)
					(thickness 0.1524)
				)
			)
		)
		(duplicate_pad_numbers_are_jumpers no)
		(fp_line
			(start 1.651 1.778)
			(end 1.651 -1.778)
			(stroke
				(width 0.1524)
				(type default)
			)
			(layer "F.SilkS")
		)
		(fp_line
			(start 1.651 -1.778)
			(end -1.651 -1.778)
			(stroke
				(width 0.1524)
				(type default)
			)
			(layer "F.SilkS")
		)
		(fp_line
			(start -1.651 1.778)
			(end 1.651 1.778)
			(stroke
				(width 0.1524)
				(type default)
			)
			(layer "F.SilkS")
		)
		(fp_line
			(start -1.651 -1.778)
			(end -1.651 1.778)
			(stroke
				(width 0.1524)
				(type default)
			)
			(layer "F.SilkS")
		)
		(fp_poly
			(pts
				(xy -1.778 1.8796) (xy -1.778 -1.8796) (xy 1.778 -1.8796) (xy 1.778 1.8796)
			)
			(stroke
				(width 0)
				(type default)
			)
			(fill no)
			(layer "F.CrtYd")
		)
		(fp_poly
			(pts
				(xy -1.778 1.8796) (xy -1.778 -1.8796) (xy 1.778 -1.8796) (xy 1.778 1.8796)
			)
			(stroke
				(width 0)
				(type default)
			)
			(fill no)
			(layer "F.Fab")
		)
		(pad "D" smd custom
			(at 0 -0.9525 180)
			(size 0.1905 0.1905)
			(layers "F.Cu" "F.Mask" "F.Paste")
			(net "LED_Q_7")
			(options
				(clearance outline)
				(anchor circle)
			)
			(primitives
				(gr_poly
					(pts
						(arc
							(start -0.1778 0.5715)
							(mid -0.321484 0.511984)
							(end -0.381 0.3683)
						)
						(arc
							(start -0.381 -0.3683)
							(mid -0.321484 -0.511984)
							(end -0.1778 -0.5715)
						)
						(arc
							(start 0.1778 -0.5715)
							(mid 0.321484 -0.511984)
							(end 0.381 -0.3683)
						)
						(arc
							(start 0.381 0.3683)
							(mid 0.321484 0.511984)
							(end 0.1778 0.5715)
						)
					)
					(width 0)
					(fill yes)
				)
			)
		)
		(pad "G" smd custom
			(at -0.98425 0.9525 180)
			(size 0.1905 0.1905)
			(layers "F.Cu" "F.Mask" "F.Paste")
			(net "UPLINK7_R")
			(options
				(clearance outline)
				(anchor circle)
			)
			(primitives
				(gr_poly
					(pts
						(arc
							(start -0.1778 0.5715)
							(mid -0.321484 0.511984)
							(end -0.381 0.3683)
						)
						(arc
							(start -0.381 -0.3683)
							(mid -0.321484 -0.511984)
							(end -0.1778 -0.5715)
						)
						(arc
							(start 0.1778 -0.5715)
							(mid 0.321484 -0.511984)
							(end 0.381 -0.3683)
						)
						(arc
							(start 0.381 0.3683)
							(mid 0.321484 0.511984)
							(end 0.1778 0.5715)
						)
					)
					(width 0)
					(fill yes)
				)
			)
		)
		(pad "S" smd custom
			(at 0.98425 0.9525 180)
			(size 0.1905 0.1905)
			(layers "F.Cu" "F.Mask" "F.Paste")
			(net "GND")
			(options
				(clearance outline)
				(anchor circle)
			)
			(primitives
				(gr_poly
					(pts
						(arc
							(start -0.1778 0.5715)
							(mid -0.321484 0.511984)
							(end -0.381 0.3683)
						)
						(arc
							(start -0.381 -0.3683)
							(mid -0.321484 -0.511984)
							(end -0.1778 -0.5715)
						)
						(arc
							(start 0.1778 -0.5715)
							(mid 0.321484 -0.511984)
							(end 0.381 -0.3683)
						)
						(arc
							(start 0.381 0.3683)
							(mid 0.321484 0.511984)
							(end 0.1778 0.5715)
						)
					)
					(width 0)
					(fill yes)
				)
			)
		)
	)
	(footprint ""
		(layer "F.Cu")
		(at 125.960124 -196.443092)
		(property "Reference" "R7921"
			(at 0 0 0)
			(layer "F.SilkS")
			(hide yes)
			(effects
				(font
					(size 1.27 1.27)
				)
			)
		)
		(property "Value" "0R2J-2-GP"
			(at 0.064008 -3.993896 0)
			(unlocked yes)
			(layer "F.Fab")
			(hide yes)
			(effects
				(font
					(size 1.016 1.016)
					(thickness 0.1524)
				)
			)
		)
		(property "Device Type" "R402H16"
			(at 0.064008 -5.517896 0)
			(unlocked yes)
			(layer "F.Fab")
			(hide yes)
			(effects
				(font
					(size 1.016 1.016)
					(thickness 0.1524)
				)
			)
		)
		(duplicate_pad_numbers_are_jumpers no)
		(fp_line
			(start -0.508 -0.9398)
			(end -0.508 0.9398)
			(stroke
				(width 0.1524)
				(type default)
			)
			(layer "F.SilkS")
		)
		(fp_line
			(start 0.508 -0.9398)
			(end -0.508 -0.9398)
			(stroke
				(width 0.1524)
				(type default)
			)
			(layer "F.SilkS")
		)
		(fp_rect
			(start -0.508 0.9398)
			(end 0.508 -0.9398)
			(stroke
				(width 0)
				(type default)
			)
			(fill no)
			(layer "F.CrtYd")
		)
		(fp_rect
			(start -0.508 0.9398)
			(end 0.508 -0.9398)
			(stroke
				(width 0)
				(type default)
			)
			(fill no)
			(layer "F.Fab")
		)
		(pad "1" smd custom
			(at 0 -0.4445)
			(size 0.1397 0.1397)
			(layers "F.Cu" "F.Mask" "F.Paste")
			(net "SSD_PRSNT#1")
			(options
				(clearance outline)
				(anchor circle)
			)
			(primitives
				(gr_poly
					(pts
						(arc
							(start -0.1778 -0.2794)
							(mid -0.249642 -0.249642)
							(end -0.2794 -0.1778)
						)
						(arc
							(start -0.2794 0.1778)
							(mid -0.249642 0.249642)
							(end -0.1778 0.2794)
						)
						(arc
							(start 0.1778 0.2794)
							(mid 0.249642 0.249642)
							(end 0.2794 0.1778)
						)
						(arc
							(start 0.2794 -0.1778)
							(mid 0.249642 -0.249642)
							(end 0.1778 -0.2794)
						)
					)
					(width 0)
					(fill yes)
				)
			)
		)
		(pad "2" smd custom
			(at 0 0.4445)
			(size 0.1397 0.1397)
			(layers "F.Cu" "F.Mask" "F.Paste")
			(net "SSD_PRSNT#1_R")
			(options
				(clearance outline)
				(anchor circle)
			)
			(primitives
				(gr_poly
					(pts
						(arc
							(start -0.1778 -0.2794)
							(mid -0.249642 -0.249642)
							(end -0.2794 -0.1778)
						)
						(arc
							(start -0.2794 0.1778)
							(mid -0.249642 0.249642)
							(end -0.1778 0.2794)
						)
						(arc
							(start 0.1778 0.2794)
							(mid 0.249642 0.249642)
							(end 0.2794 0.1778)
						)
						(arc
							(start 0.2794 -0.1778)
							(mid 0.249642 -0.249642)
							(end 0.1778 -0.2794)
						)
					)
					(width 0)
					(fill yes)
				)
			)
		)
	)
	(footprint ""
		(layer "F.Cu")
		(at 38.433756 -81.858358 -90)
		(property "Reference" "R631"
			(at 0 0 270)
			(layer "F.SilkS")
			(hide yes)
			(effects
				(font
					(size 1.27 1.27)
				)
			)
		)
		(property "Value" "47KR2F-GP"
			(at 0.064008 -3.993896 270)
			(unlocked yes)
			(layer "F.Fab")
			(hide yes)
			(effects
				(font
					(size 1.016 1.016)
					(thickness 0.1524)
				)
			)
		)
		(property "Device Type" "R402H16"
			(at 0.064008 -5.517896 270)
			(unlocked yes)
			(layer "F.Fab")
			(hide yes)
			(effects
				(font
					(size 1.016 1.016)
					(thickness 0.1524)
				)
			)
		)
		(duplicate_pad_numbers_are_jumpers no)
		(fp_line
			(start -0.508 -0.9398)
			(end -0.508 0.9398)
			(stroke
				(width 0.1524)
				(type default)
			)
			(layer "F.SilkS")
		)
		(fp_line
			(start 0.508 -0.9398)
			(end -0.508 -0.9398)
			(stroke
				(width 0.1524)
				(type default)
			)
			(layer "F.SilkS")
		)
		(fp_rect
			(start -0.508 0.9398)
			(end 0.508 -0.9398)
			(stroke
				(width 0)
				(type default)
			)
			(fill no)
			(layer "F.CrtYd")
		)
		(fp_rect
			(start -0.508 0.9398)
			(end 0.508 -0.9398)
			(stroke
				(width 0)
				(type default)
			)
			(fill no)
			(layer "F.Fab")
		)
		(pad "1" smd custom
			(at 0 -0.4445 270)
			(size 0.1397 0.1397)
			(layers "F.Cu" "F.Mask" "F.Paste")
			(net "P12V_PCIE")
			(options
				(clearance outline)
				(anchor circle)
			)
			(primitives
				(gr_poly
					(pts
						(arc
							(start -0.1778 -0.2794)
							(mid -0.249642 -0.249642)
							(end -0.2794 -0.1778)
						)
						(arc
							(start -0.2794 0.1778)
							(mid -0.249642 0.249642)
							(end -0.1778 0.2794)
						)
						(arc
							(start 0.1778 0.2794)
							(mid 0.249642 0.249642)
							(end 0.2794 0.1778)
						)
						(arc
							(start 0.2794 -0.1778)
							(mid 0.249642 -0.249642)
							(end 0.1778 -0.2794)
						)
					)
					(width 0)
					(fill yes)
				)
			)
		)
		(pad "2" smd custom
			(at 0 0.4445 270)
			(size 0.1397 0.1397)
			(layers "F.Cu" "F.Mask" "F.Paste")
			(net "Q45_D")
			(options
				(clearance outline)
				(anchor circle)
			)
			(primitives
				(gr_poly
					(pts
						(arc
							(start -0.1778 -0.2794)
							(mid -0.249642 -0.249642)
							(end -0.2794 -0.1778)
						)
						(arc
							(start -0.2794 0.1778)
							(mid -0.249642 0.249642)
							(end -0.1778 0.2794)
						)
						(arc
							(start 0.1778 0.2794)
							(mid 0.249642 0.249642)
							(end 0.2794 0.1778)
						)
						(arc
							(start 0.2794 -0.1778)
							(mid 0.249642 -0.249642)
							(end 0.1778 -0.2794)
						)
					)
					(width 0)
					(fill yes)
				)
			)
		)
	)
	(footprint ""
		(layer "F.Cu")
		(at 310.007 -60.9346)
		(property "Reference" "PG59"
			(at 0 0 0)
			(layer "F.SilkS")
			(hide yes)
			(effects
				(font
					(size 1.27 1.27)
				)
			)
		)
		(property "Value" "GAP-CLOSE-PWR-3-GP"
			(at 0.0254 -6.5786 0)
			(unlocked yes)
			(layer "F.Fab")
			(hide yes)
			(effects
				(font
					(size 1.016 1.016)
					(thickness 0.1524)
				)
			)
		)
		(property "Device Type" "GAP-CLOSE-PWR-3"
			(at 0.0254 -8.255 0)
			(unlocked yes)
			(layer "F.Fab")
			(hide yes)
			(effects
				(font
					(size 1.016 1.016)
					(thickness 0.1524)
				)
			)
		)
		(duplicate_pad_numbers_are_jumpers no)
		(fp_rect
			(start -0.7112 0.4572)
			(end 0.7112 -0.4572)
			(stroke
				(width 0)
				(type default)
			)
			(fill no)
			(layer "F.CrtYd")
		)
		(fp_poly
			(pts
				(xy -0.7112 -0.4572) (xy 0.7112 -0.4572) (xy 0.7112 0.4572) (xy -0.7112 0.4572)
			)
			(stroke
				(width 0)
				(type default)
			)
			(fill no)
			(layer "F.Fab")
		)
		(pad "1" smd rect
			(at -0.3048 0)
			(size 0.6604 0.762)
			(layers "F.Cu" "F.Mask" "F.Paste")
			(net "DUT_VDD")
		)
		(pad "2" smd rect
			(at 0.3048 0)
			(size 0.6604 0.762)
			(layers "F.Cu" "F.Mask" "F.Paste")
			(net "P0V9_E")
		)
	)
	(footprint ""
		(layer "F.Cu")
		(at 32.6136 -210.058 -90)
		(property "Reference" "D37"
			(at 0 0 270)
			(layer "F.SilkS")
			(hide yes)
			(effects
				(font
					(size 1.27 1.27)
				)
			)
		)
		(property "Value" "SMF15A-GP"
			(at -2.0955 1.2192 270)
			(unlocked yes)
			(layer "F.Fab")
			(hide yes)
			(effects
				(font
					(size 1.016 1.016)
					(thickness 0.1524)
				)
			)
		)
		(property "Device Type" "SOD123AK-2H43"
			(at -2.0955 -0.3048 270)
			(unlocked yes)
			(layer "F.Fab")
			(hide yes)
			(effects
				(font
					(size 1.016 1.016)
					(thickness 0.1524)
				)
			)
		)
		(duplicate_pad_numbers_are_jumpers no)
		(fp_line
			(start 1.1557 2.921)
			(end -1.1557 2.921)
			(stroke
				(width 0.508)
				(type default)
			)
			(layer "F.SilkS")
		)
		(fp_line
			(start -1.1557 2.7686)
			(end 1.1557 2.7686)
			(stroke
				(width 0.1524)
				(type default)
			)
			(layer "F.SilkS")
		)
		(fp_line
			(start 1.1557 2.7686)
			(end 1.1557 -2.7686)
			(stroke
				(width 0.1524)
				(type default)
			)
			(layer "F.SilkS")
		)
		(fp_line
			(start -1.1557 -2.7686)
			(end -1.1557 2.7686)
			(stroke
				(width 0.1524)
				(type default)
			)
			(layer "F.SilkS")
		)
		(fp_line
			(start 1.1557 -2.7686)
			(end -1.1557 -2.7686)
			(stroke
				(width 0.1524)
				(type default)
			)
			(layer "F.SilkS")
		)
		(fp_poly
			(pts
				(xy -0.4572 1.8669) (xy -0.4572 1.397) (xy -0.9017 1.397) (xy -0.9017 -1.397) (xy -0.4572 -1.397)
				(xy -0.4572 -1.8669) (xy 0.4572 -1.8669) (xy 0.4572 -1.397) (xy 0.9017 -1.397) (xy 0.9017 1.397)
				(xy 0.4572 1.397) (xy 0.4572 1.8669)
			)
			(stroke
				(width 0)
				(type default)
			)
			(fill no)
			(layer "F.CrtYd")
		)
		(fp_poly
			(pts
				(xy -1.4097 2.8448) (xy -1.4097 -2.8448) (xy 1.4097 -2.8448) (xy 1.4097 1.3716) (xy 0.9017 1.3716)
				(xy 0.9017 -1.397) (xy 0.4572 -1.397) (xy 0.4572 -1.8669) (xy -0.4572 -1.8669) (xy -0.4572 -1.397)
				(xy -0.9017 -1.397) (xy -0.9017 1.397) (xy -0.4572 1.397) (xy -0.4572 1.8669) (xy 0.4572 1.8669)
				(xy 0.4572 1.397) (xy 0.9017 1.397) (xy 0.9017 1.3843) (xy 1.4097 1.3843) (xy 1.4097 2.8448)
			)
			(stroke
				(width 0)
				(type default)
			)
			(fill no)
			(layer "F.CrtYd")
		)
		(fp_rect
			(start -1.4097 2.8448)
			(end 1.4097 -2.8448)
			(stroke
				(width 0)
				(type default)
			)
			(fill no)
			(layer "F.Fab")
		)
		(pad "A" smd rect
			(at 0 -1.75768 270)
			(size 1.143 1.4986)
			(layers "F.Cu" "F.Mask" "F.Paste")
			(net "GND")
		)
		(pad "K" smd rect
			(at 0 1.75768 270)
			(size 1.143 1.4986)
			(layers "F.Cu" "F.Mask" "F.Paste")
			(net "P12V_PCIE")
		)
	)
	(footprint ""
		(layer "F.Cu")
		(at 350.046036 -44.503086)
		(property "Reference" "R689"
			(at 0 0 0)
			(layer "F.SilkS")
			(hide yes)
			(effects
				(font
					(size 1.27 1.27)
				)
			)
		)
		(property "Value" "4K7R2F-GP"
			(at 0.064008 -3.993896 0)
			(unlocked yes)
			(layer "F.Fab")
			(hide yes)
			(effects
				(font
					(size 1.016 1.016)
					(thickness 0.1524)
				)
			)
		)
		(property "Device Type" "R402H16"
			(at 0.064008 -5.517896 0)
			(unlocked yes)
			(layer "F.Fab")
			(hide yes)
			(effects
				(font
					(size 1.016 1.016)
					(thickness 0.1524)
				)
			)
		)
		(duplicate_pad_numbers_are_jumpers no)
		(fp_line
			(start -0.508 -0.9398)
			(end -0.508 0.9398)
			(stroke
				(width 0.1524)
				(type default)
			)
			(layer "F.SilkS")
		)
		(fp_line
			(start 0.508 -0.9398)
			(end -0.508 -0.9398)
			(stroke
				(width 0.1524)
				(type default)
			)
			(layer "F.SilkS")
		)
		(fp_rect
			(start -0.508 0.9398)
			(end 0.508 -0.9398)
			(stroke
				(width 0)
				(type default)
			)
			(fill no)
			(layer "F.CrtYd")
		)
		(fp_rect
			(start -0.508 0.9398)
			(end 0.508 -0.9398)
			(stroke
				(width 0)
				(type default)
			)
			(fill no)
			(layer "F.Fab")
		)
		(pad "1" smd custom
			(at 0 -0.4445)
			(size 0.1397 0.1397)
			(layers "F.Cu" "F.Mask" "F.Paste")
			(net "PE1_PERST#_R")
			(options
				(clearance outline)
				(anchor circle)
			)
			(primitives
				(gr_poly
					(pts
						(arc
							(start -0.1778 -0.2794)
							(mid -0.249642 -0.249642)
							(end -0.2794 -0.1778)
						)
						(arc
							(start -0.2794 0.1778)
							(mid -0.249642 0.249642)
							(end -0.1778 0.2794)
						)
						(arc
							(start 0.1778 0.2794)
							(mid 0.249642 0.249642)
							(end 0.2794 0.1778)
						)
						(arc
							(start 0.2794 -0.1778)
							(mid 0.249642 -0.249642)
							(end 0.1778 -0.2794)
						)
					)
					(width 0)
					(fill yes)
				)
			)
		)
		(pad "2" smd custom
			(at 0 0.4445)
			(size 0.1397 0.1397)
			(layers "F.Cu" "F.Mask" "F.Paste")
			(net "P3V3_STBY")
			(options
				(clearance outline)
				(anchor circle)
			)
			(primitives
				(gr_poly
					(pts
						(arc
							(start -0.1778 -0.2794)
							(mid -0.249642 -0.249642)
							(end -0.2794 -0.1778)
						)
						(arc
							(start -0.2794 0.1778)
							(mid -0.249642 0.249642)
							(end -0.1778 0.2794)
						)
						(arc
							(start 0.1778 0.2794)
							(mid 0.249642 0.249642)
							(end 0.2794 0.1778)
						)
						(arc
							(start 0.2794 -0.1778)
							(mid 0.249642 -0.249642)
							(end 0.1778 -0.2794)
						)
					)
					(width 0)
					(fill yes)
				)
			)
		)
	)
	(footprint ""
		(layer "F.Cu")
		(at 6.35 -109.855 180)
		(property "Reference" "PR69"
			(at 0 0 180)
			(layer "F.SilkS")
			(hide yes)
			(effects
				(font
					(size 1.27 1.27)
				)
			)
		)
		(property "Value" "0R3J-0-U-GP"
			(at -0.0254 -2.5146 180)
			(unlocked yes)
			(layer "F.Fab")
			(hide yes)
			(effects
				(font
					(size 1.016 1.016)
					(thickness 0.1524)
				)
			)
		)
		(property "Device Type" "R603H22"
			(at -0.0254 -4.0386 180)
			(unlocked yes)
			(layer "F.Fab")
			(hide yes)
			(effects
				(font
					(size 1.016 1.016)
					(thickness 0.1524)
				)
			)
		)
		(duplicate_pad_numbers_are_jumpers no)
		(fp_line
			(start 0.2032 0)
			(end 0.4826 0)
			(stroke
				(width 0.2032)
				(type default)
			)
			(layer "F.SilkS")
		)
		(fp_line
			(start -0.4826 0)
			(end -0.2032 0)
			(stroke
				(width 0.2032)
				(type default)
			)
			(layer "F.SilkS")
		)
		(fp_rect
			(start -0.5842 1.3335)
			(end 0.5842 -1.3335)
			(stroke
				(width 0)
				(type default)
			)
			(fill no)
			(layer "F.CrtYd")
		)
		(fp_rect
			(start -0.5842 1.3335)
			(end 0.5842 -1.3335)
			(stroke
				(width 0)
				(type default)
			)
			(fill no)
			(layer "F.Fab")
		)
		(pad "1" smd custom
			(at 0 -0.762 180)
			(size 0.2159 0.2159)
			(layers "F.Cu" "F.Mask" "F.Paste")
			(net "P3V3_STBY")
			(options
				(clearance outline)
				(anchor circle)
			)
			(primitives
				(gr_poly
					(pts
						(arc
							(start -0.3302 -0.4318)
							(mid -0.402042 -0.402042)
							(end -0.4318 -0.3302)
						)
						(arc
							(start -0.4318 0.3302)
							(mid -0.402042 0.402042)
							(end -0.3302 0.4318)
						)
						(arc
							(start 0.3302 0.4318)
							(mid 0.402042 0.402042)
							(end 0.4318 0.3302)
						)
						(arc
							(start 0.4318 -0.3302)
							(mid 0.402042 -0.402042)
							(end 0.3302 -0.4318)
						)
					)
					(width 0)
					(fill yes)
				)
			)
		)
		(pad "2" smd custom
			(at 0 0.762 180)
			(size 0.2159 0.2159)
			(layers "F.Cu" "F.Mask" "F.Paste")
			(net "VR_P1V26_STBY_IN")
			(options
				(clearance outline)
				(anchor circle)
			)
			(primitives
				(gr_poly
					(pts
						(arc
							(start -0.3302 -0.4318)
							(mid -0.402042 -0.402042)
							(end -0.4318 -0.3302)
						)
						(arc
							(start -0.4318 0.3302)
							(mid -0.402042 0.402042)
							(end -0.3302 0.4318)
						)
						(arc
							(start 0.3302 0.4318)
							(mid 0.402042 0.402042)
							(end 0.4318 0.3302)
						)
						(arc
							(start 0.4318 -0.3302)
							(mid 0.402042 -0.402042)
							(end 0.3302 -0.4318)
						)
					)
					(width 0)
					(fill yes)
				)
			)
		)
	)
)
